(kicad_pcb
	(version 20260206)
	(generator "pcbnew")
	(generator_version "10.0")
	(general
		(thickness 1.6)
		(legacy_teardrops no)
	)
	(paper "A4")
	(title_block
		(title "04192023_DAF0TMB3IC0_F0TG_MB_C_brd_V02_OCP.brd")
		(comment 1 "Grand Teton / footprint 4371 of 8354 (J26), pads 227-291 of 291")
	)
	(layers
		(0 "F.Cu" signal "TOP")
		(4 "In1.Cu" signal "GND")
		(6 "In2.Cu" signal "IN1")
		(8 "In3.Cu" signal "GND1")
		(10 "In4.Cu" signal "IN2")
		(12 "In5.Cu" signal "GND2")
		(14 "In6.Cu" signal "IN3")
		(16 "In7.Cu" signal "GND3")
		(18 "In8.Cu" signal "VCC")
		(20 "In9.Cu" signal "VCC1")
		(22 "In10.Cu" signal "GND4")
		(24 "In11.Cu" signal "IN4")
		(26 "In12.Cu" signal "GND5")
		(28 "In13.Cu" signal "IN5")
		(30 "In14.Cu" signal "GND6")
		(32 "In15.Cu" signal "IN6")
		(34 "In16.Cu" signal "GND7")
		(2 "B.Cu" signal "BOTTOM")
		(9 "F.Adhes" user "F.Adhesive")
		(11 "B.Adhes" user "B.Adhesive")
		(13 "F.Paste" user "Package Geometry/Pastemask Top")
		(15 "B.Paste" user "Package Geometry/Pastemask Bottom")
		(5 "F.SilkS" user "Ref Des/Silkscreen Top")
		(7 "B.SilkS" user "Ref Des/Silkscreen Bottom")
		(1 "F.Mask" user "Board Geometry/Soldermask Top")
		(3 "B.Mask" user "Board Geometry/Soldermask Bottom")
		(17 "Dwgs.User" user "User.Drawings")
		(19 "Cmts.User" user "User.Comments")
		(21 "Eco1.User" user "User.Eco1")
		(23 "Eco2.User" user "User.Eco2")
		(25 "Edge.Cuts" user "Board Geometry/Outline")
		(27 "Margin" user)
		(31 "F.CrtYd" user "Package Geometry/Place Bound Top")
		(29 "B.CrtYd" user "Package Geometry/Place Bound Bottom")
		(35 "F.Fab" user "Ref Des/Assembly Top")
		(33 "B.Fab" user "Ref Des/Assembly Bottom")
	)
	(footprint ""
		(layer "F.Cu")
		(at 49.834038 -255.560322 180)
		(property "Reference" "J26"
			(at -0.703326 -82.357722 0)
			(unlocked yes)
			(layer "F.SilkS")
			(effects
				(font
					(size 0.7874 0.5842)
					(thickness 0.1524)
				)
			)
		)
		(property "Value" ""
			(at 0 0 180)
			(layer "F.Fab")
			(effects
				(font
					(size 1.27 1.27)
				)
			)
		)
		(duplicate_pad_numbers_are_jumpers no)
		(pad "227" smd rect
			(at 2.050034 11.474958 90)
			(size 0.519938 1.4986)
			(layers "F.Cu" "F.Mask" "F.Paste")
			(net "M_B_CPU1_SB_PAR")
		)
		(pad "228" smd rect
			(at 2.050034 12.325096 90)
			(size 0.519938 1.4986)
			(layers "F.Cu" "F.Mask" "F.Paste")
			(net "GND")
		)
		(pad "229" smd rect
			(at 2.050034 13.17498 90)
			(size 0.519938 1.4986)
			(layers "F.Cu" "F.Mask" "F.Paste")
			(net "M_B_CPU1_SB_CS_N<1>")
		)
		(pad "230" smd rect
			(at 2.050034 14.025118 90)
			(size 0.519938 1.4986)
			(layers "F.Cu" "F.Mask" "F.Paste")
			(net "GND")
		)
		(pad "231" smd rect
			(at 2.050034 14.875002 90)
			(size 0.519938 1.4986)
			(layers "F.Cu" "F.Mask" "F.Paste")
			(net "Net_2275")
		)
		(pad "232" smd rect
			(at 2.050034 15.724886 90)
			(size 0.519938 1.4986)
			(layers "F.Cu" "F.Mask" "F.Paste")
			(net "Net_2276")
		)
		(pad "233" smd rect
			(at 2.050034 16.575024 90)
			(size 0.519938 1.4986)
			(layers "F.Cu" "F.Mask" "F.Paste")
			(net "GND")
		)
		(pad "234" smd rect
			(at 2.050034 17.424908 90)
			(size 0.519938 1.4986)
			(layers "F.Cu" "F.Mask" "F.Paste")
			(net "M_B_CPU1_SB_CB<6>")
		)
		(pad "235" smd rect
			(at 2.050034 18.275046 90)
			(size 0.519938 1.4986)
			(layers "F.Cu" "F.Mask" "F.Paste")
			(net "GND")
		)
		(pad "236" smd rect
			(at 2.050034 19.12493 90)
			(size 0.519938 1.4986)
			(layers "F.Cu" "F.Mask" "F.Paste")
			(net "M_B_CPU1_SB_CB<7>")
		)
		(pad "237" smd rect
			(at 2.050034 19.975068 90)
			(size 0.519938 1.4986)
			(layers "F.Cu" "F.Mask" "F.Paste")
			(net "GND")
		)
		(pad "238" smd rect
			(at 2.050034 20.824952 90)
			(size 0.519938 1.4986)
			(layers "F.Cu" "F.Mask" "F.Paste")
			(net "M_B_CPU1_SB_DQS_DN<4>")
		)
		(pad "239" smd rect
			(at 2.050034 21.67509 90)
			(size 0.519938 1.4986)
			(layers "F.Cu" "F.Mask" "F.Paste")
			(net "M_B_CPU1_SB_DQS_DP<4>")
		)
		(pad "240" smd rect
			(at 2.050034 22.524974 90)
			(size 0.519938 1.4986)
			(layers "F.Cu" "F.Mask" "F.Paste")
			(net "GND")
		)
		(pad "241" smd rect
			(at 2.050034 23.375112 90)
			(size 0.519938 1.4986)
			(layers "F.Cu" "F.Mask" "F.Paste")
			(net "M_B_CPU1_SB_CB<2>")
		)
		(pad "242" smd rect
			(at 2.050034 24.224996 90)
			(size 0.519938 1.4986)
			(layers "F.Cu" "F.Mask" "F.Paste")
			(net "GND")
		)
		(pad "243" smd rect
			(at 2.050034 25.07488 90)
			(size 0.519938 1.4986)
			(layers "F.Cu" "F.Mask" "F.Paste")
			(net "M_B_CPU1_SB_CB<3>")
		)
		(pad "244" smd rect
			(at 2.050034 25.925018 90)
			(size 0.519938 1.4986)
			(layers "F.Cu" "F.Mask" "F.Paste")
			(net "GND")
		)
		(pad "245" smd rect
			(at 2.050034 26.774902 90)
			(size 0.519938 1.4986)
			(layers "F.Cu" "F.Mask" "F.Paste")
			(net "M_B_CPU1_SB_DQ<2>")
		)
		(pad "246" smd rect
			(at 2.050034 27.62504 90)
			(size 0.519938 1.4986)
			(layers "F.Cu" "F.Mask" "F.Paste")
			(net "GND")
		)
		(pad "247" smd rect
			(at 2.050034 28.474924 90)
			(size 0.519938 1.4986)
			(layers "F.Cu" "F.Mask" "F.Paste")
			(net "M_B_CPU1_SB_DQ<3>")
		)
		(pad "248" smd rect
			(at 2.050034 29.325062 90)
			(size 0.519938 1.4986)
			(layers "F.Cu" "F.Mask" "F.Paste")
			(net "GND")
		)
		(pad "249" smd rect
			(at 2.050034 30.174946 90)
			(size 0.519938 1.4986)
			(layers "F.Cu" "F.Mask" "F.Paste")
			(net "M_B_CPU1_SB_DQS_DN<5>")
		)
		(pad "250" smd rect
			(at 2.050034 31.025084 90)
			(size 0.519938 1.4986)
			(layers "F.Cu" "F.Mask" "F.Paste")
			(net "M_B_CPU1_SB_DQS_DP<5>")
		)
		(pad "251" smd rect
			(at 2.050034 31.874968 90)
			(size 0.519938 1.4986)
			(layers "F.Cu" "F.Mask" "F.Paste")
			(net "GND")
		)
		(pad "252" smd rect
			(at 2.050034 32.725106 90)
			(size 0.519938 1.4986)
			(layers "F.Cu" "F.Mask" "F.Paste")
			(net "M_B_CPU1_SB_DQ<6>")
		)
		(pad "253" smd rect
			(at 2.050034 33.57499 90)
			(size 0.519938 1.4986)
			(layers "F.Cu" "F.Mask" "F.Paste")
			(net "GND")
		)
		(pad "254" smd rect
			(at 2.050034 34.425128 90)
			(size 0.519938 1.4986)
			(layers "F.Cu" "F.Mask" "F.Paste")
			(net "M_B_CPU1_SB_DQ<7>")
		)
		(pad "255" smd rect
			(at 2.050034 35.275012 90)
			(size 0.519938 1.4986)
			(layers "F.Cu" "F.Mask" "F.Paste")
			(net "GND")
		)
		(pad "256" smd rect
			(at 2.050034 36.124896 90)
			(size 0.519938 1.4986)
			(layers "F.Cu" "F.Mask" "F.Paste")
			(net "M_B_CPU1_SB_DQ<10>")
		)
		(pad "257" smd rect
			(at 2.050034 36.975034 90)
			(size 0.519938 1.4986)
			(layers "F.Cu" "F.Mask" "F.Paste")
			(net "GND")
		)
		(pad "258" smd rect
			(at 2.050034 37.824918 90)
			(size 0.519938 1.4986)
			(layers "F.Cu" "F.Mask" "F.Paste")
			(net "M_B_CPU1_SB_DQ<11>")
		)
		(pad "259" smd rect
			(at 2.050034 38.675056 90)
			(size 0.519938 1.4986)
			(layers "F.Cu" "F.Mask" "F.Paste")
			(net "GND")
		)
		(pad "260" smd rect
			(at 2.050034 39.52494 90)
			(size 0.519938 1.4986)
			(layers "F.Cu" "F.Mask" "F.Paste")
			(net "M_B_CPU1_SB_DQS_DN<6>")
		)
		(pad "261" smd rect
			(at 2.050034 40.375078 90)
			(size 0.519938 1.4986)
			(layers "F.Cu" "F.Mask" "F.Paste")
			(net "M_B_CPU1_SB_DQS_DP<6>")
		)
		(pad "262" smd rect
			(at 2.050034 41.224962 90)
			(size 0.519938 1.4986)
			(layers "F.Cu" "F.Mask" "F.Paste")
			(net "GND")
		)
		(pad "263" smd rect
			(at 2.050034 42.0751 90)
			(size 0.519938 1.4986)
			(layers "F.Cu" "F.Mask" "F.Paste")
			(net "M_B_CPU1_SB_DQ<14>")
		)
		(pad "264" smd rect
			(at 2.050034 42.924984 90)
			(size 0.519938 1.4986)
			(layers "F.Cu" "F.Mask" "F.Paste")
			(net "GND")
		)
		(pad "265" smd rect
			(at 2.050034 43.775122 90)
			(size 0.519938 1.4986)
			(layers "F.Cu" "F.Mask" "F.Paste")
			(net "M_B_CPU1_SB_DQ<15>")
		)
		(pad "266" smd rect
			(at 2.050034 44.625006 90)
			(size 0.519938 1.4986)
			(layers "F.Cu" "F.Mask" "F.Paste")
			(net "GND")
		)
		(pad "267" smd rect
			(at 2.050034 45.47489 90)
			(size 0.519938 1.4986)
			(layers "F.Cu" "F.Mask" "F.Paste")
			(net "M_B_CPU1_SB_DQ<18>")
		)
		(pad "268" smd rect
			(at 2.050034 46.325028 90)
			(size 0.519938 1.4986)
			(layers "F.Cu" "F.Mask" "F.Paste")
			(net "GND")
		)
		(pad "269" smd rect
			(at 2.050034 47.174912 90)
			(size 0.519938 1.4986)
			(layers "F.Cu" "F.Mask" "F.Paste")
			(net "M_B_CPU1_SB_DQ<19>")
		)
		(pad "270" smd rect
			(at 2.050034 48.02505 90)
			(size 0.519938 1.4986)
			(layers "F.Cu" "F.Mask" "F.Paste")
			(net "GND")
		)
		(pad "271" smd rect
			(at 2.050034 48.874934 90)
			(size 0.519938 1.4986)
			(layers "F.Cu" "F.Mask" "F.Paste")
			(net "M_B_CPU1_SB_DQS_DN<7>")
		)
		(pad "272" smd rect
			(at 2.050034 49.725072 90)
			(size 0.519938 1.4986)
			(layers "F.Cu" "F.Mask" "F.Paste")
			(net "M_B_CPU1_SB_DQS_DP<7>")
		)
		(pad "273" smd rect
			(at 2.050034 50.574956 90)
			(size 0.519938 1.4986)
			(layers "F.Cu" "F.Mask" "F.Paste")
			(net "GND")
		)
		(pad "274" smd rect
			(at 2.050034 51.425094 90)
			(size 0.519938 1.4986)
			(layers "F.Cu" "F.Mask" "F.Paste")
			(net "M_B_CPU1_SB_DQ<22>")
		)
		(pad "275" smd rect
			(at 2.050034 52.274978 90)
			(size 0.519938 1.4986)
			(layers "F.Cu" "F.Mask" "F.Paste")
			(net "GND")
		)
		(pad "276" smd rect
			(at 2.050034 53.125116 90)
			(size 0.519938 1.4986)
			(layers "F.Cu" "F.Mask" "F.Paste")
			(net "M_B_CPU1_SB_DQ<23>")
		)
		(pad "277" smd rect
			(at 2.050034 53.975 90)
			(size 0.519938 1.4986)
			(layers "F.Cu" "F.Mask" "F.Paste")
			(net "GND")
		)
		(pad "278" smd rect
			(at 2.050034 54.824884 90)
			(size 0.519938 1.4986)
			(layers "F.Cu" "F.Mask" "F.Paste")
			(net "M_B_CPU1_SB_DQ<26>")
		)
		(pad "279" smd rect
			(at 2.050034 55.675022 90)
			(size 0.519938 1.4986)
			(layers "F.Cu" "F.Mask" "F.Paste")
			(net "GND")
		)
		(pad "280" smd rect
			(at 2.050034 56.524906 90)
			(size 0.519938 1.4986)
			(layers "F.Cu" "F.Mask" "F.Paste")
			(net "M_B_CPU1_SB_DQ<27>")
		)
		(pad "281" smd rect
			(at 2.050034 57.375044 90)
			(size 0.519938 1.4986)
			(layers "F.Cu" "F.Mask" "F.Paste")
			(net "GND")
		)
		(pad "282" smd rect
			(at 2.050034 58.224928 90)
			(size 0.519938 1.4986)
			(layers "F.Cu" "F.Mask" "F.Paste")
			(net "M_B_CPU1_SB_DQS_DN<8>")
		)
		(pad "283" smd rect
			(at 2.050034 59.075066 90)
			(size 0.519938 1.4986)
			(layers "F.Cu" "F.Mask" "F.Paste")
			(net "M_B_CPU1_SB_DQS_DP<8>")
		)
		(pad "284" smd rect
			(at 2.050034 59.92495 90)
			(size 0.519938 1.4986)
			(layers "F.Cu" "F.Mask" "F.Paste")
			(net "GND")
		)
		(pad "285" smd rect
			(at 2.050034 60.775088 90)
			(size 0.519938 1.4986)
			(layers "F.Cu" "F.Mask" "F.Paste")
			(net "M_B_CPU1_SB_DQ<30>")
		)
		(pad "286" smd rect
			(at 2.050034 61.624972 90)
			(size 0.519938 1.4986)
			(layers "F.Cu" "F.Mask" "F.Paste")
			(net "GND")
		)
		(pad "287" smd rect
			(at 2.050034 62.47511 90)
			(size 0.519938 1.4986)
			(layers "F.Cu" "F.Mask" "F.Paste")
			(net "M_B_CPU1_SB_DQ<31>")
		)
		(pad "288" smd rect
			(at 2.050034 63.324994 90)
			(size 0.519938 1.4986)
			(layers "F.Cu" "F.Mask" "F.Paste")
			(net "GND")
		)
		(pad "G1" thru_hole oval
			(at 0 -68.97497 90)
			(size 1.7272 3.4798)
			(drill oval 1.2192 2.4638)
			(layers "*.Cu" "*.Mask")
			(remove_unused_layers no)
			(net "GND")
			(clearance 0.127)
			(thermal_gap 0.127)
		)
		(pad "G2" thru_hole oval
			(at 0 3.875024 90)
			(size 1.7272 3.4798)
			(drill oval 1.2192 2.4638)
			(layers "*.Cu" "*.Mask")
			(remove_unused_layers no)
			(net "GND")
			(clearance 0.127)
			(thermal_gap 0.127)
		)
		(pad "G3" thru_hole oval
			(at 0 68.97497 90)
			(size 1.7272 3.4798)
			(drill oval 1.2192 2.4638)
			(layers "*.Cu" "*.Mask")
			(remove_unused_layers no)
			(net "GND")
			(clearance 0.127)
			(thermal_gap 0.127)
		)
	)
)
